(kicad_pcb
	(version 20241229)
	(generator "pcbnew")
	(generator_version "9.0")
	(general
		(thickness 1.61)
		(legacy_teardrops no)
	)
	(paper "A3")
	(title_block
		(title "SO-DIMM DDR5 Tester")
		(date "2025-11-26")
		(rev "1.3.0")
		(comment 9 "footprints 620-625 of 627")
	)
	(layers
		(0 "F.Cu" signal)
		(4 "In1.Cu" power)
		(6 "In2.Cu" mixed)
		(8 "In3.Cu" power)
		(10 "In4.Cu" mixed)
		(12 "In5.Cu" power)
		(14 "In6.Cu" mixed)
		(16 "In7.Cu" power)
		(18 "In8.Cu" power)
		(20 "In9.Cu" mixed)
		(22 "In10.Cu" power)
		(2 "B.Cu" signal)
		(9 "F.Adhes" user "F.Adhesive")
		(11 "B.Adhes" user "B.Adhesive")
		(13 "F.Paste" user)
		(15 "B.Paste" user)
		(5 "F.SilkS" user "F.Silkscreen")
		(7 "B.SilkS" user "B.Silkscreen")
		(1 "F.Mask" user)
		(3 "B.Mask" user)
		(17 "Dwgs.User" user "User.Drawings")
		(19 "Cmts.User" user "User.Comments")
		(21 "Eco1.User" user "User.Eco1")
		(23 "Eco2.User" user "User.Eco2")
		(25 "Edge.Cuts" user)
		(27 "Margin" user)
		(31 "F.CrtYd" user "F.Courtyard")
		(29 "B.CrtYd" user "B.Courtyard")
		(35 "F.Fab" user)
		(33 "B.Fab" user)
	)
	(footprint "antmicro-footprints:TP_SMD_1mm"
		(layer "B.Cu")
		(at 191.69 189.26 180)
		(property "Reference" "TP58"
			(at -1.22 -1.72 0)
			(layer "B.SilkS")
			(effects
				(font
					(size 0.7 0.7)
					(thickness 0.15)
				)
				(justify left bottom mirror)
			)
		)
		(property "Value" "TP_1mm_SMD"
			(at 0 -1.4 0)
			(layer "B.Fab")
			(effects
				(font
					(size 0.7 0.7)
					(thickness 0.15)
				)
				(justify left bottom mirror)
			)
		)
		(property "MPN" ""
			(at 0 0 0)
			(unlocked yes)
			(layer "B.Fab")
			(hide yes)
			(effects
				(font
					(size 1 1)
					(thickness 0.15)
				)
				(justify mirror)
			)
		)
		(property "Manufacturer" ""
			(at 0 0 0)
			(unlocked yes)
			(layer "B.Fab")
			(hide yes)
			(effects
				(font
					(size 1 1)
					(thickness 0.15)
				)
				(justify mirror)
			)
		)
		(property "Author" "Antmicro"
			(at 0 0 0)
			(unlocked yes)
			(layer "B.Fab")
			(hide yes)
			(effects
				(font
					(size 1 1)
					(thickness 0.15)
				)
				(justify mirror)
			)
		)
		(property "License" "Apache-2.0"
			(at 0 0 0)
			(unlocked yes)
			(layer "B.Fab")
			(hide yes)
			(effects
				(font
					(size 1 1)
					(thickness 0.15)
				)
				(justify mirror)
			)
		)
		(sheetname "/Supply/")
		(sheetfile "supply.kicad_sch")
		(attr exclude_from_pos_files)
		(fp_circle
			(center 0 0)
			(end 0.6 0)
			(stroke
				(width 0.05)
				(type default)
			)
			(fill no)
			(layer "B.CrtYd")
		)
		(fp_text user "License: Apache-2.0"
			(at -0.5 -5.2 0)
			(layer "B.Fab")
			(effects
				(font
					(size 0.7 0.7)
					(thickness 0.15)
				)
				(justify left bottom mirror)
			)
		)
		(fp_text user "Author: Antmicro"
			(at -0.5 -4 0)
			(layer "B.Fab")
			(effects
				(font
					(size 0.7 0.7)
					(thickness 0.15)
				)
				(justify left bottom mirror)
			)
		)
		(fp_text user "${REFERENCE}"
			(at -0.5 -2.8 0)
			(layer "B.Fab")
			(effects
				(font
					(size 0.7 0.7)
					(thickness 0.15)
				)
				(justify left bottom mirror)
			)
		)
		(pad "1" smd circle
			(at 0 0 180)
			(size 1 1)
			(layers "B.Cu" "B.Mask")
			(net 42 "/Supply/MGTAVCC_local")
			(pinfunction "1")
			(pintype "passive")
		)
	)
	(footprint "antmicro-footprints:R_0402_1005Metric"
		(layer "B.Cu")
		(at 196.575 142.3)
		(descr "Resistor SMD 0402")
		(tags "resistor SMD 0402")
		(property "Reference" "R172"
			(at -1.122484 0.772697 180)
			(layer "B.SilkS")
			(hide yes)
			(effects
				(font
					(size 0.7 0.7)
					(thickness 0.15)
				)
				(justify left bottom mirror)
			)
		)
		(property "Value" "R_47k_0402"
			(at -1.011843 -1.772047 180)
			(layer "B.Fab")
			(effects
				(font
					(size 0.7 0.7)
					(thickness 0.15)
				)
				(justify left bottom mirror)
			)
		)
		(property "Datasheet" "https://www.bourns.com/docs/product-datasheets/cr.pdf"
			(at 0 0 0)
			(layer "F.Fab")
			(hide yes)
			(effects
				(font
					(size 1.27 1.27)
					(thickness 0.15)
				)
			)
		)
		(property "Author" "Antmicro"
			(at 0 0 0)
			(layer "B.Fab")
			(hide yes)
			(effects
				(font
					(size 1 1)
					(thickness 0.15)
				)
				(justify mirror)
			)
		)
		(property "License" "Apache-2.0"
			(at 0 0 0)
			(layer "B.Fab")
			(hide yes)
			(effects
				(font
					(size 1 1)
					(thickness 0.15)
				)
				(justify mirror)
			)
		)
		(property "MPN" "CR0402-FX-4702GLF"
			(at 0 0 0)
			(layer "B.Fab")
			(hide yes)
			(effects
				(font
					(size 1 1)
					(thickness 0.15)
				)
				(justify mirror)
			)
		)
		(property "Manufacturer" "Bourns"
			(at 0 0 0)
			(layer "B.Fab")
			(hide yes)
			(effects
				(font
					(size 1 1)
					(thickness 0.15)
				)
				(justify mirror)
			)
		)
		(property "Tolerance" "1%"
			(at 0 0 0)
			(layer "B.Fab")
			(hide yes)
			(effects
				(font
					(size 1 1)
					(thickness 0.15)
				)
				(justify mirror)
			)
		)
		(property "Val" "47k"
			(at 0 0 0)
			(layer "B.Fab")
			(hide yes)
			(effects
				(font
					(size 1 1)
					(thickness 0.15)
				)
				(justify mirror)
			)
		)
		(sheetname "/Supply/")
		(sheetfile "supply.kicad_sch")
		(attr smd)
		(fp_rect
			(start -0.93 0.47)
			(end 0.93 -0.47)
			(stroke
				(width 0.05)
				(type solid)
			)
			(fill no)
			(layer "B.CrtYd")
		)
		(fp_rect
			(start -0.5 0.25)
			(end 0.5 -0.25)
			(stroke
				(width 0.15)
				(type solid)
			)
			(fill no)
			(layer "B.Fab")
		)
		(pad "1" smd roundrect
			(at -0.485 0)
			(size 0.59 0.64)
			(layers "B.Cu" "B.Mask" "B.Paste")
			(roundrect_rratio 0.25)
			(net 367 "Net-(Q16-D)")
			(pintype "passive")
		)
		(pad "2" smd roundrect
			(at 0.485 0)
			(size 0.59 0.64)
			(layers "B.Cu" "B.Mask" "B.Paste")
			(roundrect_rratio 0.25)
			(net 41 "+3V3_AON")
			(pintype "passive")
		)
	)
	(footprint "antmicro-footprints:C_0402_1005Metric"
		(layer "B.Cu")
		(at 114.800502 183.8)
		(descr "Capacitor SMD 0402")
		(tags "capacitor SMD 0402")
		(property "Reference" "C5"
			(at 0 0.699 180)
			(layer "B.SilkS")
			(hide yes)
			(effects
				(font
					(size 0.7 0.7)
					(thickness 0.15)
				)
				(justify left bottom mirror)
			)
		)
		(property "Value" "C_100n_0402"
			(at -1.022927 -2.155213 180)
			(layer "B.Fab")
			(effects
				(font
					(size 0.7 0.7)
					(thickness 0.15)
				)
				(justify left bottom mirror)
			)
		)
		(property "Datasheet" "https://www.murata.com/products/productdetail?partno=GRM155R61H104KE14%23"
			(at 0 0 0)
			(layer "F.Fab")
			(hide yes)
			(effects
				(font
					(size 1.27 1.27)
					(thickness 0.15)
				)
			)
		)
		(property "Author" "Antmicro"
			(at 0 0 0)
			(layer "B.Fab")
			(hide yes)
			(effects
				(font
					(size 1 1)
					(thickness 0.15)
				)
				(justify mirror)
			)
		)
		(property "Dielectric" "X5R"
			(at 0 0 0)
			(layer "B.Fab")
			(hide yes)
			(effects
				(font
					(size 1 1)
					(thickness 0.15)
				)
				(justify mirror)
			)
		)
		(property "License" "Apache-2.0"
			(at 0 0 0)
			(layer "B.Fab")
			(hide yes)
			(effects
				(font
					(size 1 1)
					(thickness 0.15)
				)
				(justify mirror)
			)
		)
		(property "MPN" "GRM155R61H104KE14D"
			(at 0 0 0)
			(layer "B.Fab")
			(hide yes)
			(effects
				(font
					(size 1 1)
					(thickness 0.15)
				)
				(justify mirror)
			)
		)
		(property "Manufacturer" "Murata"
			(at 0 0 0)
			(layer "B.Fab")
			(hide yes)
			(effects
				(font
					(size 1 1)
					(thickness 0.15)
				)
				(justify mirror)
			)
		)
		(property "Val" "100n"
			(at 0 0 0)
			(layer "B.Fab")
			(hide yes)
			(effects
				(font
					(size 1 1)
					(thickness 0.15)
				)
				(justify mirror)
			)
		)
		(property "Voltage" "50V"
			(at 0 0 0)
			(layer "B.Fab")
			(hide yes)
			(effects
				(font
					(size 1 1)
					(thickness 0.15)
				)
				(justify mirror)
			)
		)
		(sheetname "/HyperRAM + QSPI Flash/")
		(sheetfile "hyperram-flash.kicad_sch")
		(attr smd)
		(fp_rect
			(start -0.9659 0.481258)
			(end 0.9649 -0.458742)
			(stroke
				(width 0.05)
				(type solid)
			)
			(fill no)
			(layer "B.CrtYd")
		)
		(fp_line
			(start -0.499 -0.248)
			(end -0.499 0.25)
			(stroke
				(width 0.15)
				(type solid)
			)
			(layer "B.Fab")
		)
		(fp_line
			(start -0.499 0.25)
			(end 0.499 0.25)
			(stroke
				(width 0.15)
				(type solid)
			)
			(layer "B.Fab")
		)
		(fp_line
			(start 0.499 -0.248)
			(end -0.499 -0.248)
			(stroke
				(width 0.15)
				(type solid)
			)
			(layer "B.Fab")
		)
		(fp_line
			(start 0.499 0.25)
			(end 0.499 -0.248)
			(stroke
				(width 0.15)
				(type solid)
			)
			(layer "B.Fab")
		)
		(pad "1" smd roundrect
			(at -0.484 0)
			(size 0.59 0.64)
			(layers "B.Cu" "B.Mask" "B.Paste")
			(roundrect_rratio 0.25)
			(net 200 "+3V3")
			(pintype "passive")
		)
		(pad "2" smd roundrect
			(at 0.484 0)
			(size 0.59 0.64)
			(layers "B.Cu" "B.Mask" "B.Paste")
			(roundrect_rratio 0.25)
			(net 1 "GND")
			(pintype "passive")
		)
	)
	(footprint "antmicro-footprints:R_0402_1005Metric"
		(layer "B.Cu")
		(at 133.75 142.4 -90)
		(descr "Resistor SMD 0402")
		(tags "resistor SMD 0402")
		(property "Reference" "R25"
			(at -3.044968 -0.354606 90)
			(layer "B.SilkS")
			(effects
				(font
					(size 0.7 0.7)
					(thickness 0.15)
				)
				(justify left bottom mirror)
			)
		)
		(property "Value" "R_47k_0402"
			(at -1.011843 -1.772047 90)
			(layer "B.Fab")
			(effects
				(font
					(size 0.7 0.7)
					(thickness 0.15)
				)
				(justify left bottom mirror)
			)
		)
		(property "Datasheet" "https://www.bourns.com/docs/product-datasheets/cr.pdf"
			(at 0 0 270)
			(layer "F.Fab")
			(hide yes)
			(effects
				(font
					(size 1.27 1.27)
					(thickness 0.15)
				)
			)
		)
		(property "Author" "Antmicro"
			(at -8.65 276.15 0)
			(layer "B.Fab")
			(hide yes)
			(effects
				(font
					(size 1 1)
					(thickness 0.15)
				)
				(justify mirror)
			)
		)
		(property "License" "Apache-2.0"
			(at -8.65 276.15 0)
			(layer "B.Fab")
			(hide yes)
			(effects
				(font
					(size 1 1)
					(thickness 0.15)
				)
				(justify mirror)
			)
		)
		(property "MPN" "CR0402-FX-4702GLF"
			(at -8.65 276.15 0)
			(layer "B.Fab")
			(hide yes)
			(effects
				(font
					(size 1 1)
					(thickness 0.15)
				)
				(justify mirror)
			)
		)
		(property "Manufacturer" "Bourns"
			(at -8.65 276.15 0)
			(layer "B.Fab")
			(hide yes)
			(effects
				(font
					(size 1 1)
					(thickness 0.15)
				)
				(justify mirror)
			)
		)
		(property "Tolerance" "1%"
			(at -8.65 276.15 0)
			(layer "B.Fab")
			(hide yes)
			(effects
				(font
					(size 1 1)
					(thickness 0.15)
				)
				(justify mirror)
			)
		)
		(property "Val" "47k"
			(at -8.65 276.15 0)
			(layer "B.Fab")
			(hide yes)
			(effects
				(font
					(size 1 1)
					(thickness 0.15)
				)
				(justify mirror)
			)
		)
		(sheetname "/DDR5 SODIMM/")
		(sheetfile "ddr5-sodimm.kicad_sch")
		(attr smd)
		(fp_rect
			(start -0.93 0.47)
			(end 0.93 -0.47)
			(stroke
				(width 0.05)
				(type solid)
			)
			(fill no)
			(layer "B.CrtYd")
		)
		(fp_rect
			(start -0.5 0.25)
			(end 0.5 -0.25)
			(stroke
				(width 0.15)
				(type solid)
			)
			(fill no)
			(layer "B.Fab")
		)
		(pad "1" smd roundrect
			(at -0.485 0 270)
			(size 0.59 0.64)
			(layers "B.Cu" "B.Mask" "B.Paste")
			(roundrect_rratio 0.25)
			(net 140 "/DDR5 SODIMM/VSS_DET1")
			(pintype "passive")
		)
		(pad "2" smd roundrect
			(at 0.485 0 270)
			(size 0.59 0.64)
			(layers "B.Cu" "B.Mask" "B.Paste")
			(roundrect_rratio 0.25)
			(net 200 "+3V3")
			(pintype "passive")
		)
	)
	(footprint "antmicro-footprints:R_0402_1005Metric"
		(layer "B.Cu")
		(at 139 142.4 -90)
		(descr "Resistor SMD 0402")
		(tags "resistor SMD 0402")
		(property "Reference" "R28"
			(at -3.044968 -0.354606 90)
			(layer "B.SilkS")
			(effects
				(font
					(size 0.7 0.7)
					(thickness 0.15)
				)
				(justify left bottom mirror)
			)
		)
		(property "Value" "R_0R_0402"
			(at -1.011843 -1.772047 90)
			(layer "B.Fab")
			(effects
				(font
					(size 0.7 0.7)
					(thickness 0.15)
				)
				(justify left bottom mirror)
			)
		)
		(property "Datasheet" "https://industrial.panasonic.com/cdbs/www-data/pdf/RDA0000/AOA0000C301.pdf"
			(at 0 0 270)
			(layer "F.Fab")
			(hide yes)
			(effects
				(font
					(size 1.27 1.27)
					(thickness 0.15)
				)
			)
		)
		(property "Author" "Antmicro"
			(at -3.4 281.4 0)
			(layer "B.Fab")
			(hide yes)
			(effects
				(font
					(size 1 1)
					(thickness 0.15)
				)
				(justify mirror)
			)
		)
		(property "Current" "1A"
			(at -3.4 281.4 0)
			(layer "B.Fab")
			(hide yes)
			(effects
				(font
					(size 1 1)
					(thickness 0.15)
				)
				(justify mirror)
			)
		)
		(property "License" "Apache-2.0"
			(at -3.4 281.4 0)
			(layer "B.Fab")
			(hide yes)
			(effects
				(font
					(size 1 1)
					(thickness 0.15)
				)
				(justify mirror)
			)
		)
		(property "MPN" "ERJ2GE0R00X"
			(at -3.4 281.4 0)
			(layer "B.Fab")
			(hide yes)
			(effects
				(font
					(size 1 1)
					(thickness 0.15)
				)
				(justify mirror)
			)
		)
		(property "Manufacturer" "Panasonic"
			(at -3.4 281.4 0)
			(layer "B.Fab")
			(hide yes)
			(effects
				(font
					(size 1 1)
					(thickness 0.15)
				)
				(justify mirror)
			)
		)
		(property "Tolerance" ""
			(at -3.4 281.4 0)
			(layer "B.Fab")
			(hide yes)
			(effects
				(font
					(size 1 1)
					(thickness 0.15)
				)
				(justify mirror)
			)
		)
		(property "Val" "0R"
			(at -3.4 281.4 0)
			(layer "B.Fab")
			(hide yes)
			(effects
				(font
					(size 1 1)
					(thickness 0.15)
				)
				(justify mirror)
			)
		)
		(sheetname "/DDR5 SODIMM/")
		(sheetfile "ddr5-sodimm.kicad_sch")
		(attr smd)
		(fp_rect
			(start -0.93 0.47)
			(end 0.93 -0.47)
			(stroke
				(width 0.05)
				(type solid)
			)
			(fill no)
			(layer "B.CrtYd")
		)
		(fp_rect
			(start -0.5 0.25)
			(end 0.5 -0.25)
			(stroke
				(width 0.15)
				(type solid)
			)
			(fill no)
			(layer "B.Fab")
		)
		(pad "1" smd roundrect
			(at -0.485 0 270)
			(size 0.59 0.64)
			(layers "B.Cu" "B.Mask" "B.Paste")
			(roundrect_rratio 0.25)
			(net 172 "/DDR5 SODIMM/VSS_DET2")
			(pintype "passive")
		)
		(pad "2" smd roundrect
			(at 0.485 0 270)
			(size 0.59 0.64)
			(layers "B.Cu" "B.Mask" "B.Paste")
			(roundrect_rratio 0.25)
			(net 249 "TB_DETECT")
			(pintype "passive")
		)
	)
	(footprint "antmicro-footprints:C_0402_1005Metric"
		(layer "B.Cu")
		(at 131.375501 170.801 90)
		(descr "Capacitor SMD 0402 (1005 Metric), square (rectangular) end terminal, IPC_7351 nominal, (Body size source: IPC-SM-782 page 76, https://www.pcb-3d.com/wordpress/wp-content/uploads/ipc-sm-782a_amendment_1_and_2.pdf)")
		(tags "capacitor 0402")
		(property "Reference" "C52"
			(at 0 1.17 270)
			(layer "B.SilkS")
			(hide yes)
			(effects
				(font
					(size 0.7 0.7)
					(thickness 0.15)
				)
				(justify left bottom mirror)
			)
		)
		(property "Value" "C_100n_0402"
			(at 0 -1.169 270)
			(layer "B.Fab")
			(effects
				(font
					(size 0.7 0.7)
					(thickness 0.15)
				)
				(justify left bottom mirror)
			)
		)
		(property "Datasheet" "https://www.murata.com/products/productdetail?partno=GRM155R61H104KE14%23"
			(at 0 0 90)
			(layer "F.Fab")
			(hide yes)
			(effects
				(font
					(size 1.27 1.27)
					(thickness 0.15)
				)
			)
		)
		(property "Author" "Antmicro"
			(at 302.176501 39.425499 0)
			(layer "B.Fab")
			(hide yes)
			(effects
				(font
					(size 1 1)
					(thickness 0.15)
				)
				(justify mirror)
			)
		)
		(property "Dielectric" "X5R"
			(at 302.176501 39.425499 0)
			(layer "B.Fab")
			(hide yes)
			(effects
				(font
					(size 1 1)
					(thickness 0.15)
				)
				(justify mirror)
			)
		)
		(property "License" "Apache-2.0"
			(at 302.176501 39.425499 0)
			(layer "B.Fab")
			(hide yes)
			(effects
				(font
					(size 1 1)
					(thickness 0.15)
				)
				(justify mirror)
			)
		)
		(property "MPN" "GRM155R61H104KE14D"
			(at 302.176501 39.425499 0)
			(layer "B.Fab")
			(hide yes)
			(effects
				(font
					(size 1 1)
					(thickness 0.15)
				)
				(justify mirror)
			)
		)
		(property "Manufacturer" "Murata"
			(at 302.176501 39.425499 0)
			(layer "B.Fab")
			(hide yes)
			(effects
				(font
					(size 1 1)
					(thickness 0.15)
				)
				(justify mirror)
			)
		)
		(property "Val" "100n"
			(at 302.176501 39.425499 0)
			(layer "B.Fab")
			(hide yes)
			(effects
				(font
					(size 1 1)
					(thickness 0.15)
				)
				(justify mirror)
			)
		)
		(property "Voltage" "50V"
			(at 302.176501 39.425499 0)
			(layer "B.Fab")
			(hide yes)
			(effects
				(font
					(size 1 1)
					(thickness 0.15)
				)
				(justify mirror)
			)
		)
		(sheetname "/FPGA power/")
		(sheetfile "fpga-power.kicad_sch")
		(attr smd)
		(fp_rect
			(start -0.9656 0.4572)
			(end 0.9652 -0.4828)
			(stroke
				(width 0.05)
				(type solid)
			)
			(fill no)
			(layer "B.CrtYd")
		)
		(fp_line
			(start 0.498 -0.248)
			(end -0.5 -0.248)
			(stroke
				(width 0.15)
				(type solid)
			)
			(layer "B.Fab")
		)
		(fp_line
			(start -0.5 -0.248)
			(end -0.5 0.25)
			(stroke
				(width 0.15)
				(type solid)
			)
			(layer "B.Fab")
		)
		(fp_line
			(start 0.498 0.25)
			(end 0.498 -0.248)
			(stroke
				(width 0.15)
				(type solid)
			)
			(layer "B.Fab")
		)
		(fp_line
			(start -0.5 0.25)
			(end 0.498 0.25)
			(stroke
				(width 0.15)
				(type solid)
			)
			(layer "B.Fab")
		)
		(pad "1" smd roundrect
			(at -0.5 0)
			(size 0.6 0.6)
			(layers "B.Cu" "B.Mask" "B.Paste")
			(roundrect_rratio 0.25)
			(net 1 "GND")
			(pintype "passive")
		)
		(pad "2" smd roundrect
			(at 0.498 0 90)
			(size 0.6 0.6)
			(layers "B.Cu" "B.Mask" "B.Paste")
			(roundrect_rratio 0.25)
			(net 200 "+3V3")
			(pintype "passive")
		)
	)
)
